# BASEBOARD_FAB2 (Tioga Pass) — schematic netlist excerpt (pin names and nets, part order shuffled) for the footprints in the layout excerpt that follows; sources: Cadence DE-HDL packaged netlist, KiCad conversion of Wiwynn_Tioga_Pass_MB.brd

R1W24  RES  0.0 5% CHIP  pkg 0402  page 101 : A = XTAL_CK_MNG_OUT ; B = XTAL_CK_MNG_OUT_R
RT25  RES  0 5.0% CHIP  pkg 0603  page 203 : A = VR_PVCCIN_CPU0_PH3_BOOT ; B = VR_PVCCIN_CPU0_PH3_BOOT_R
R8F11  RES  0.0 5% CHIP  pkg 0402  page 240 : A = GND ; B = AGND_P3V3_STBY

(kicad_pcb
	(version 20260206)
	(generator "pcbnew")
	(generator_version "10.0")
	(general
		(thickness 1.6)
		(legacy_teardrops no)
	)
	(paper "A4")
	(title_block
		(title "Wiwynn_Tioga_Pass_MB.brd")
		(comment 1 "Tioga Pass / footprints 1028-1030 of 4770")
	)
	(layers
		(0 "F.Cu" signal "TOP")
		(4 "In1.Cu" signal "L2GND")
		(6 "In2.Cu" signal "L3")
		(8 "In3.Cu" signal "L4GND")
		(10 "In4.Cu" signal "L5")
		(12 "In5.Cu" signal "L6GND")
		(14 "In6.Cu" signal "L7VCC")
		(16 "In7.Cu" signal "L8VCC")
		(18 "In8.Cu" signal "L9GND")
		(20 "In9.Cu" signal "L10")
		(22 "In10.Cu" signal "L11GND")
		(24 "In11.Cu" signal "L12")
		(26 "In12.Cu" signal "L13GND")
		(2 "B.Cu" signal "BOTTOM")
		(9 "F.Adhes" user "F.Adhesive")
		(11 "B.Adhes" user "B.Adhesive")
		(13 "F.Paste" user "Package Geometry/Pastemask Top")
		(15 "B.Paste" user "Package Geometry/Pastemask Bottom")
		(5 "F.SilkS" user "Ref Des/Silkscreen Top")
		(7 "B.SilkS" user "Ref Des/Silkscreen Bottom")
		(1 "F.Mask" user "Board Geometry/Soldermask Top")
		(3 "B.Mask" user "Board Geometry/Soldermask Bottom")
		(17 "Dwgs.User" user "User.Drawings")
		(19 "Cmts.User" user "User.Comments")
		(21 "Eco1.User" user "User.Eco1")
		(23 "Eco2.User" user "User.Eco2")
		(25 "Edge.Cuts" user "Board Geometry/Outline")
		(27 "Margin" user)
		(31 "F.CrtYd" user "Package Geometry/Place Bound Top")
		(29 "B.CrtYd" user "Package Geometry/Place Bound Bottom")
		(35 "F.Fab" user "Ref Des/Assembly Top")
		(33 "B.Fab" user "Ref Des/Assembly Bottom")
	)
	(footprint ""
		(layer "F.Cu")
		(at 469.138 -20.6502 -90)
		(property "Reference" "R8F11"
			(at 0 0 270)
			(layer "F.SilkS")
			(hide yes)
			(effects
				(font
					(size 1.27 1.27)
				)
			)
		)
		(property "Value" ""
			(at 0 0 270)
			(layer "F.Fab")
			(effects
				(font
					(size 1.27 1.27)
				)
			)
		)
		(duplicate_pad_numbers_are_jumpers no)
		(fp_rect
			(start 0.2794 0.9906)
			(end -0.2794 -0.1016)
			(stroke
				(width 0)
				(type default)
			)
			(fill no)
			(layer "F.CrtYd")
		)
		(fp_line
			(start -0.2794 0.9906)
			(end 0.2794 0.9906)
			(stroke
				(width 0.1)
				(type default)
			)
			(layer "F.Fab")
		)
		(fp_line
			(start 0.2794 0.9906)
			(end 0.2794 -0.1016)
			(stroke
				(width 0.1)
				(type default)
			)
			(layer "F.Fab")
		)
		(fp_line
			(start -0.2794 -0.1016)
			(end -0.2794 0.9906)
			(stroke
				(width 0.1)
				(type default)
			)
			(layer "F.Fab")
		)
		(fp_line
			(start 0.2794 -0.1016)
			(end -0.2794 -0.1016)
			(stroke
				(width 0.1)
				(type default)
			)
			(layer "F.Fab")
		)
		(pad "1" smd rect
			(at 0 0 270)
			(size 0.508 0.508)
			(layers "F.Cu" "F.Mask" "F.Paste")
			(net "GND")
		)
		(pad "2" smd rect
			(at 0 0.889 270)
			(size 0.508 0.508)
			(layers "F.Cu" "F.Mask" "F.Paste")
			(net "AGND_P3V3_STBY")
		)
		(zone
			(layer "F.Cu")
			(hatch none 0.5)
			(connect_pads
				(clearance 0)
			)
			(min_thickness 0.25)
			(keepout
				(tracks allowed)
				(vias not_allowed)
				(pads allowed)
				(copperpour not_allowed)
				(footprints allowed)
			)
			(placement
				(enabled no)
				(sheetname "")
			)
			(fill
				(thermal_gap 0.5)
				(thermal_bridge_width 0.5)
				(island_removal_mode 0)
			)
			(polygon
				(pts
					(xy 468.503 -20.3962) (xy 468.884 -20.3962) (xy 468.884 -20.9042) (xy 468.503 -20.9042)
				)
			)
		)
		(zone
			(layer "F.Cu")
			(hatch none 0.5)
			(connect_pads
				(clearance 0)
			)
			(min_thickness 0.25)
			(keepout
				(tracks not_allowed)
				(vias allowed)
				(pads allowed)
				(copperpour not_allowed)
				(footprints allowed)
			)
			(placement
				(enabled no)
				(sheetname "")
			)
			(fill
				(thermal_gap 0.5)
				(thermal_bridge_width 0.5)
				(island_removal_mode 0)
			)
			(polygon
				(pts
					(xy 468.503 -20.3962) (xy 468.884 -20.3962) (xy 468.884 -20.9042) (xy 468.503 -20.9042)
				)
			)
		)
	)
	(footprint ""
		(layer "F.Cu")
		(at 192.0748 -74.168 90)
		(property "Reference" "RT25"
			(at 1.01473 0.656336 0)
			(unlocked yes)
			(layer "F.SilkS")
			(effects
				(font
					(size 0.4064 0.254)
					(thickness 0.1524)
				)
			)
		)
		(property "Value" ""
			(at 0 0 90)
			(layer "F.Fab")
			(effects
				(font
					(size 1.27 1.27)
				)
			)
		)
		(duplicate_pad_numbers_are_jumpers no)
		(fp_poly
			(pts
				(xy -0.4953 -0.2032) (xy 0.4953 -0.2032) (xy 0.4953 1.6002) (xy -0.4953 1.6002)
			)
			(stroke
				(width 0)
				(type default)
			)
			(fill no)
			(layer "F.CrtYd")
		)
		(fp_line
			(start 0.4953 -0.2032)
			(end 0.4953 1.6002)
			(stroke
				(width 0.1)
				(type default)
			)
			(layer "F.Fab")
		)
		(fp_line
			(start -0.4953 -0.2032)
			(end 0.4953 -0.2032)
			(stroke
				(width 0.1)
				(type default)
			)
			(layer "F.Fab")
		)
		(fp_line
			(start 0.4953 1.6002)
			(end -0.4953 1.6002)
			(stroke
				(width 0.1)
				(type default)
			)
			(layer "F.Fab")
		)
		(fp_line
			(start -0.4953 1.6002)
			(end -0.4953 -0.2032)
			(stroke
				(width 0.1)
				(type default)
			)
			(layer "F.Fab")
		)
		(pad "1" smd rect
			(at 0 0 90)
			(size 0.762 0.889)
			(layers "F.Cu" "F.Mask" "F.Paste")
			(net "VR_PVCCIN_CPU0_PH3_BOOT")
		)
		(pad "2" smd rect
			(at 0 1.397 90)
			(size 0.762 0.889)
			(layers "F.Cu" "F.Mask" "F.Paste")
			(net "VR_PVCCIN_CPU0_PH3_BOOT_R")
		)
		(zone
			(layer "F.Cu")
			(hatch none 0.5)
			(connect_pads
				(clearance 0)
			)
			(min_thickness 0.25)
			(keepout
				(tracks allowed)
				(vias not_allowed)
				(pads allowed)
				(copperpour not_allowed)
				(footprints allowed)
			)
			(placement
				(enabled no)
				(sheetname "")
			)
			(fill
				(thermal_gap 0.5)
				(thermal_bridge_width 0.5)
				(island_removal_mode 0)
			)
			(polygon
				(pts
					(xy 193.0273 -74.549) (xy 192.5193 -74.549) (xy 192.5193 -73.787) (xy 193.0273 -73.787)
				)
			)
		)
		(zone
			(layer "F.Cu")
			(hatch none 0.5)
			(connect_pads
				(clearance 0)
			)
			(min_thickness 0.25)
			(keepout
				(tracks not_allowed)
				(vias allowed)
				(pads allowed)
				(copperpour not_allowed)
				(footprints allowed)
			)
			(placement
				(enabled no)
				(sheetname "")
			)
			(fill
				(thermal_gap 0.5)
				(thermal_bridge_width 0.5)
				(island_removal_mode 0)
			)
			(polygon
				(pts
					(xy 193.0273 -73.787) (xy 193.0273 -74.549) (xy 192.5193 -74.549) (xy 192.5193 -73.787)
				)
			)
		)
	)
	(footprint ""
		(layer "F.Cu")
		(at 482.6508 -33.909)
		(property "Reference" "R1W24"
			(at -0.8382 -0.67818 0)
			(unlocked yes)
			(layer "F.SilkS")
			(effects
				(font
					(size 0.4064 0.254)
					(thickness 0.1524)
				)
				(justify left)
			)
		)
		(property "Value" ""
			(at 0 0 0)
			(layer "F.Fab")
			(effects
				(font
					(size 1.27 1.27)
				)
			)
		)
		(duplicate_pad_numbers_are_jumpers no)
		(fp_poly
			(pts
				(xy -0.2794 -0.1016) (xy 0.2794 -0.1016) (xy 0.2794 0.9906) (xy -0.2794 0.9906)
			)
			(stroke
				(width 0)
				(type default)
			)
			(fill no)
			(layer "F.CrtYd")
		)
		(fp_line
			(start -0.2794 -0.1016)
			(end -0.2794 0.9906)
			(stroke
				(width 0.1)
				(type default)
			)
			(layer "F.Fab")
		)
		(fp_line
			(start -0.2794 0.9906)
			(end 0.2794 0.9906)
			(stroke
				(width 0.1)
				(type default)
			)
			(layer "F.Fab")
		)
		(fp_line
			(start 0.2794 -0.1016)
			(end -0.2794 -0.1016)
			(stroke
				(width 0.1)
				(type default)
			)
			(layer "F.Fab")
		)
		(fp_line
			(start 0.2794 0.9906)
			(end 0.2794 -0.1016)
			(stroke
				(width 0.1)
				(type default)
			)
			(layer "F.Fab")
		)
		(pad "1" smd rect
			(at 0 0)
			(size 0.508 0.508)
			(layers "F.Cu" "F.Mask" "F.Paste")
			(net "XTAL_CK_MNG_OUT")
		)
		(pad "2" smd rect
			(at 0 0.889)
			(size 0.508 0.508)
			(layers "F.Cu" "F.Mask" "F.Paste")
			(net "XTAL_CK_MNG_OUT_R")
		)
		(zone
			(layer "F.Cu")
			(hatch none 0.5)
			(connect_pads
				(clearance 0)
			)
			(min_thickness 0.25)
			(keepout
				(tracks allowed)
				(vias not_allowed)
				(pads allowed)
				(copperpour not_allowed)
				(footprints allowed)
			)
			(placement
				(enabled no)
				(sheetname "")
			)
			(fill
				(thermal_gap 0.5)
				(thermal_bridge_width 0.5)
				(island_removal_mode 0)
			)
			(polygon
				(pts
					(xy 482.3968 -33.655) (xy 482.9048 -33.655) (xy 482.9048 -33.274) (xy 482.3968 -33.274)
				)
			)
		)
		(zone
			(layer "F.Cu")
			(hatch none 0.5)
			(connect_pads
				(clearance 0)
			)
			(min_thickness 0.25)
			(keepout
				(tracks not_allowed)
				(vias allowed)
				(pads allowed)
				(copperpour not_allowed)
				(footprints allowed)
			)
			(placement
				(enabled no)
				(sheetname "")
			)
			(fill
				(thermal_gap 0.5)
				(thermal_bridge_width 0.5)
				(island_removal_mode 0)
			)
			(polygon
				(pts
					(xy 482.3968 -33.274) (xy 482.9048 -33.274) (xy 482.9048 -33.655) (xy 482.3968 -33.655)
				)
			)
		)
	)
)
